(kicad_pcb
	(version 20241229)
	(generator "pcbnew")
	(generator_version "9.0")
	(general
		(thickness 1.711)
		(legacy_teardrops no)
	)
	(paper "A4")
	(title_block
		(title "Antmicro Baseboard for Jetson AGX Thor")
		(date "2026-02-18")
		(rev "1.1.0")
		(company "Antmicro Ltd")
		(comment 1 "www.antmicro.com")
		(comment 9 "footprints 1074-1077 of 1170")
	)
	(layers
		(0 "F.Cu" signal)
		(4 "In1.Cu" signal)
		(6 "In2.Cu" signal)
		(8 "In3.Cu" signal)
		(10 "In4.Cu" jumper)
		(12 "In5.Cu" signal)
		(14 "In6.Cu" signal)
		(16 "In7.Cu" signal)
		(18 "In8.Cu" signal)
		(2 "B.Cu" signal)
		(9 "F.Adhes" user "F.Adhesive")
		(11 "B.Adhes" user "B.Adhesive")
		(13 "F.Paste" user)
		(15 "B.Paste" user)
		(5 "F.SilkS" user "F.Silkscreen")
		(7 "B.SilkS" user "B.Silkscreen")
		(1 "F.Mask" user)
		(3 "B.Mask" user)
		(17 "Dwgs.User" user "User.Drawings")
		(19 "Cmts.User" user "User.Comments")
		(21 "Eco1.User" user "User.Eco1")
		(23 "Eco2.User" user "User.Eco2")
		(25 "Edge.Cuts" user)
		(27 "Margin" user)
		(31 "F.CrtYd" user "F.Courtyard")
		(29 "B.CrtYd" user "B.Courtyard")
		(35 "F.Fab" user)
		(33 "B.Fab" user)
	)
	(footprint "antmicro-footprints:R_0402_1005Metric"
		(layer "B.Cu")
		(at 214.6 102)
		(descr "Resistor SMD 0402")
		(tags "resistor SMD 0402")
		(property "Reference" "R267"
			(at -3.775 -0.4 0)
			(layer "B.SilkS")
			(effects
				(font
					(size 0.7 0.7)
					(thickness 0.15)
				)
				(justify right top mirror)
			)
		)
		(property "Value" "R_887k_0402"
			(at -1.011843 -1.772046 0)
			(layer "B.Fab")
			(effects
				(font
					(size 0.7 0.7)
					(thickness 0.15)
				)
				(justify right top mirror)
			)
		)
		(property "Datasheet" "https://eu.mouser.com/datasheet/2/315/AOA0000C304-1149620.pdf"
			(at 0 0 0)
			(layer "B.Fab")
			(hide yes)
			(effects
				(font
					(size 1.27 1.27)
					(thickness 0.15)
				)
				(justify mirror)
			)
		)
		(property "Description" "SMD Chip Resistor"
			(at 0 0 0)
			(layer "B.Fab")
			(hide yes)
			(effects
				(font
					(size 1.27 1.27)
					(thickness 0.15)
				)
				(justify mirror)
			)
		)
		(property "MPN" "ERJ-2RKF8873X"
			(at 0 0 180)
			(unlocked yes)
			(layer "B.Fab")
			(hide yes)
			(effects
				(font
					(size 1 1)
					(thickness 0.15)
				)
				(justify mirror)
			)
		)
		(property "Manufacturer" "Panasonic"
			(at 0 0 180)
			(unlocked yes)
			(layer "B.Fab")
			(hide yes)
			(effects
				(font
					(size 1 1)
					(thickness 0.15)
				)
				(justify mirror)
			)
		)
		(property "License" "Apache-2.0"
			(at 0 0 180)
			(unlocked yes)
			(layer "B.Fab")
			(hide yes)
			(effects
				(font
					(size 1 1)
					(thickness 0.15)
				)
				(justify mirror)
			)
		)
		(property "Author" "Antmicro"
			(at 0 0 180)
			(unlocked yes)
			(layer "B.Fab")
			(hide yes)
			(effects
				(font
					(size 1 1)
					(thickness 0.15)
				)
				(justify mirror)
			)
		)
		(property "Val" "887k"
			(at 0 0 180)
			(unlocked yes)
			(layer "B.Fab")
			(hide yes)
			(effects
				(font
					(size 1 1)
					(thickness 0.15)
				)
				(justify mirror)
			)
		)
		(property "Tolerance" "1%"
			(at 0 0 180)
			(unlocked yes)
			(layer "B.Fab")
			(hide yes)
			(effects
				(font
					(size 1 1)
					(thickness 0.15)
				)
				(justify mirror)
			)
		)
		(sheetname "/Recovery USB/")
		(sheetfile "recovery_usb.kicad_sch")
		(attr smd)
		(fp_poly
			(pts
				(xy -0.925 0.47) (xy 0.925 0.47) (xy 0.925 -0.47) (xy -0.925 -0.47)
			)
			(stroke
				(width 0.05)
				(type default)
			)
			(fill no)
			(layer "B.CrtYd")
		)
		(fp_poly
			(pts
				(xy -0.5 0.25) (xy 0.5 0.25) (xy 0.5 -0.25) (xy -0.5 -0.25)
			)
			(stroke
				(width 0.15)
				(type solid)
			)
			(fill no)
			(layer "B.Fab")
		)
		(fp_text user "License: Apache-2.0"
			(at -0.949999 -5.169 0)
			(layer "B.Fab")
			(effects
				(font
					(size 0.7 0.7)
					(thickness 0.15)
				)
				(justify right top mirror)
			)
		)
		(fp_text user "${REFERENCE}"
			(at -0.95 -3.168 0)
			(layer "B.Fab")
			(effects
				(font
					(size 0.7 0.7)
					(thickness 0.15)
				)
				(justify right top mirror)
			)
		)
		(fp_text user "Author: Antmicro"
			(at -0.95 -4.169 0)
			(layer "B.Fab")
			(effects
				(font
					(size 0.7 0.7)
					(thickness 0.15)
				)
				(justify right top mirror)
			)
		)
		(pad "1" smd roundrect
			(at -0.48 0)
			(size 0.59 0.64)
			(layers "B.Cu" "B.Mask" "B.Paste")
			(roundrect_rratio 0.25)
			(net 1246 "/Recovery USB/USBC2_VBUS_DET_MUX")
			(pintype "passive")
		)
		(pad "2" smd roundrect
			(at 0.48 0)
			(size 0.59 0.64)
			(layers "B.Cu" "B.Mask" "B.Paste")
			(roundrect_rratio 0.25)
			(net 287 "/Recovery USB/USBC2_VBUS")
			(pintype "passive")
		)
	)
	(footprint "antmicro-footprints:R_0402_1005Metric"
		(layer "B.Cu")
		(at 65.4 65.7 -90)
		(descr "Resistor SMD 0402")
		(tags "resistor SMD 0402")
		(property "Reference" "R171"
			(at 0.9 -0.5 90)
			(layer "B.SilkS")
			(effects
				(font
					(size 0.7 0.7)
					(thickness 0.15)
				)
				(justify left bottom mirror)
			)
		)
		(property "Value" "R_2k2_0402"
			(at -1.011843 -1.772047 90)
			(layer "B.Fab")
			(effects
				(font
					(size 0.7 0.7)
					(thickness 0.15)
				)
				(justify left bottom mirror)
			)
		)
		(property "Datasheet" "https://www.bourns.com/docs/product-datasheets/cr.pdf"
			(at 0 0 90)
			(layer "B.Fab")
			(hide yes)
			(effects
				(font
					(size 1.27 1.27)
					(thickness 0.15)
				)
				(justify mirror)
			)
		)
		(property "Description" "SMD Chip Resistor, 2.2 kohm, ± 1%, 62.5 mW, 0402 [1005 Metric], Thick Film, General Purpose"
			(at 0 0 90)
			(layer "B.Fab")
			(hide yes)
			(effects
				(font
					(size 1.27 1.27)
					(thickness 0.15)
				)
				(justify mirror)
			)
		)
		(property "MPN" "CR0402-FX-2201GLF"
			(at 0 0 90)
			(unlocked yes)
			(layer "B.Fab")
			(hide yes)
			(effects
				(font
					(size 1 1)
					(thickness 0.15)
				)
				(justify mirror)
			)
		)
		(property "Manufacturer" "Bourns"
			(at 0 0 90)
			(unlocked yes)
			(layer "B.Fab")
			(hide yes)
			(effects
				(font
					(size 1 1)
					(thickness 0.15)
				)
				(justify mirror)
			)
		)
		(property "License" "Apache-2.0"
			(at 0 0 90)
			(unlocked yes)
			(layer "B.Fab")
			(hide yes)
			(effects
				(font
					(size 1 1)
					(thickness 0.15)
				)
				(justify mirror)
			)
		)
		(property "Author" "Antmicro"
			(at 0 0 90)
			(unlocked yes)
			(layer "B.Fab")
			(hide yes)
			(effects
				(font
					(size 1 1)
					(thickness 0.15)
				)
				(justify mirror)
			)
		)
		(property "Val" "2k2"
			(at 0 0 90)
			(unlocked yes)
			(layer "B.Fab")
			(hide yes)
			(effects
				(font
					(size 1 1)
					(thickness 0.15)
				)
				(justify mirror)
			)
		)
		(property "Tolerance" "1%"
			(at 0 0 90)
			(unlocked yes)
			(layer "B.Fab")
			(hide yes)
			(effects
				(font
					(size 1 1)
					(thickness 0.15)
				)
				(justify mirror)
			)
		)
		(sheetname "/CSI/")
		(sheetfile "csi.kicad_sch")
		(attr smd)
		(fp_rect
			(start -0.925 0.47)
			(end 0.925 -0.47)
			(stroke
				(width 0.05)
				(type default)
			)
			(fill no)
			(layer "B.CrtYd")
		)
		(fp_rect
			(start -0.5 0.25)
			(end 0.5 -0.25)
			(stroke
				(width 0.15)
				(type solid)
			)
			(fill no)
			(layer "B.Fab")
		)
		(fp_text user "${REFERENCE}"
			(at -0.95 -3.168 90)
			(layer "B.Fab")
			(effects
				(font
					(size 0.7 0.7)
					(thickness 0.15)
				)
				(justify left bottom mirror)
			)
		)
		(fp_text user "License: Apache-2.0"
			(at -0.95 -5.169 90)
			(layer "B.Fab")
			(effects
				(font
					(size 0.7 0.7)
					(thickness 0.15)
				)
				(justify left bottom mirror)
			)
		)
		(fp_text user "Author: Antmicro"
			(at -0.95 -4.169 90)
			(layer "B.Fab")
			(effects
				(font
					(size 0.7 0.7)
					(thickness 0.15)
				)
				(justify left bottom mirror)
			)
		)
		(pad "1" smd roundrect
			(at -0.48 0 270)
			(size 0.59 0.64)
			(layers "B.Cu" "B.Mask" "B.Paste")
			(roundrect_rratio 0.25)
			(net 990 "/CSI/CSIB_I2C_VCC")
			(pintype "passive")
		)
		(pad "2" smd roundrect
			(at 0.48 0 270)
			(size 0.59 0.64)
			(layers "B.Cu" "B.Mask" "B.Paste")
			(roundrect_rratio 0.25)
			(net 993 "/CSI/SDA_CAM2")
			(pintype "passive")
		)
	)
	(footprint "antmicro-footprints:SOT-23-6"
		(layer "B.Cu")
		(at 179.245 80.38 90)
		(property "Reference" "U62"
			(at -0.92 -2.645 90)
			(layer "B.SilkS")
			(effects
				(font
					(size 0.7 0.7)
					(thickness 0.15)
				)
				(justify right top mirror)
			)
		)
		(property "Value" "LTC4412IS6"
			(at -1.75 -2.693 90)
			(layer "B.Fab")
			(effects
				(font
					(size 0.7 0.7)
					(thickness 0.15)
				)
				(justify right top mirror)
			)
		)
		(property "Datasheet" "https://www.analog.com/media/en/technical-documentation/data-sheets/4412fb.pdf"
			(at 0 0.057 90)
			(layer "B.Fab")
			(hide yes)
			(effects
				(font
					(size 1.27 1.27)
					(thickness 0.15)
				)
				(justify mirror)
			)
		)
		(property "Description" "Ideal diode controller"
			(at 0 0.057 90)
			(layer "B.Fab")
			(hide yes)
			(effects
				(font
					(size 1.27 1.27)
					(thickness 0.15)
				)
				(justify mirror)
			)
		)
		(property "MPN" "LTC4412IS6#TRMPBF"
			(at 0 0 270)
			(unlocked yes)
			(layer "B.Fab")
			(hide yes)
			(effects
				(font
					(size 1 1)
					(thickness 0.15)
				)
				(justify mirror)
			)
		)
		(property "Manufacturer" "Analog Devices"
			(at 0 0 270)
			(unlocked yes)
			(layer "B.Fab")
			(hide yes)
			(effects
				(font
					(size 1 1)
					(thickness 0.15)
				)
				(justify mirror)
			)
		)
		(property "Author" "Antmicro"
			(at 0 0 270)
			(unlocked yes)
			(layer "B.Fab")
			(hide yes)
			(effects
				(font
					(size 1 1)
					(thickness 0.15)
				)
				(justify mirror)
			)
		)
		(property "License" "Apache-2.0"
			(at 0 0 270)
			(unlocked yes)
			(layer "B.Fab")
			(hide yes)
			(effects
				(font
					(size 1 1)
					(thickness 0.15)
				)
				(justify mirror)
			)
		)
		(sheetname "/Power/")
		(sheetfile "power.kicad_sch")
		(attr smd exclude_from_pos_files exclude_from_bom dnp)
		(fp_line
			(start 1.45 -0.643)
			(end 1.45 -0.343)
			(stroke
				(width 0.12)
				(type solid)
			)
			(layer "B.SilkS")
		)
		(fp_line
			(start 1.3 -0.643)
			(end 1.45 -0.643)
			(stroke
				(width 0.12)
				(type solid)
			)
			(layer "B.SilkS")
		)
		(fp_line
			(start -1.45 -0.643)
			(end -1.45 -0.343)
			(stroke
				(width 0.12)
				(type solid)
			)
			(layer "B.SilkS")
		)
		(fp_line
			(start 1.45 0.757)
			(end 1.45 0.457)
			(stroke
				(width 0.12)
				(type solid)
			)
			(layer "B.SilkS")
		)
		(fp_line
			(start 1.3 0.757)
			(end 1.45 0.757)
			(stroke
				(width 0.12)
				(type solid)
			)
			(layer "B.SilkS")
		)
		(fp_line
			(start -1.3 0.757)
			(end -1.45 0.757)
			(stroke
				(width 0.12)
				(type solid)
			)
			(layer "B.SilkS")
		)
		(fp_line
			(start -1.45 0.757)
			(end -1.45 0.457)
			(stroke
				(width 0.12)
				(type solid)
			)
			(layer "B.SilkS")
		)
		(fp_rect
			(start -1.55 1.85)
			(end 1.55 -1.75)
			(stroke
				(width 0.05)
				(type solid)
			)
			(fill no)
			(layer "B.CrtYd")
		)
		(fp_line
			(start 1.5 -0.643)
			(end -1.5 -0.643)
			(stroke
				(width 0.1)
				(type solid)
			)
			(layer "B.Fab")
		)
		(fp_line
			(start -1.5 -0.643)
			(end -1.5 0.757)
			(stroke
				(width 0.1)
				(type solid)
			)
			(layer "B.Fab")
		)
		(fp_line
			(start 1.5 0.757)
			(end 1.5 -0.643)
			(stroke
				(width 0.1)
				(type solid)
			)
			(layer "B.Fab")
		)
		(fp_line
			(start -1.5 0.757)
			(end 1.5 0.757)
			(stroke
				(width 0.1)
				(type solid)
			)
			(layer "B.Fab")
		)
		(fp_text user "."
			(at -1.3 -2.495 90)
			(layer "B.SilkS")
			(effects
				(font
					(size 1 1)
					(thickness 0.15)
				)
				(justify mirror)
			)
		)
		(fp_text user "License: Apache-2.0"
			(at -1.75 -6.5 90)
			(layer "B.Fab")
			(effects
				(font
					(size 0.7 0.7)
					(thickness 0.15)
				)
				(justify right top mirror)
			)
		)
		(fp_text user "Author: Antmicro"
			(at -1.829 -5.25 90)
			(layer "B.Fab")
			(effects
				(font
					(size 0.7 0.7)
					(thickness 0.15)
				)
				(justify right top mirror)
			)
		)
		(fp_text user "${REFERENCE}"
			(at -1.75 -4 90)
			(layer "B.Fab")
			(effects
				(font
					(size 0.7 0.7)
					(thickness 0.15)
				)
				(justify right top mirror)
			)
		)
		(pad "1" smd roundrect
			(at -0.954 -1.1 90)
			(size 0.55 1)
			(layers "B.Cu" "B.Mask" "B.Paste")
			(roundrect_rratio 0.15)
			(net 525 "/Power/USBPD2_HV")
			(pinfunction "IN")
			(pintype "power_in")
		)
		(pad "2" smd roundrect
			(at -0.003 -1.1 90)
			(size 0.55 1)
			(layers "B.Cu" "B.Mask" "B.Paste")
			(roundrect_rratio 0.15)
			(net 1 "GND")
			(pinfunction "GND")
			(pintype "power_in")
		)
		(pad "3" smd roundrect
			(at 0.947 -1.1 90)
			(size 0.55 1)
			(layers "B.Cu" "B.Mask" "B.Paste")
			(roundrect_rratio 0.15)
			(net 1 "GND")
			(pinfunction "CTL")
			(pintype "input")
		)
		(pad "4" smd roundrect
			(at 0.947 1.214 90)
			(size 0.55 1)
			(layers "B.Cu" "B.Mask" "B.Paste")
			(roundrect_rratio 0.15)
			(net 1225 "unconnected-(U62-STAT-Pad4)")
			(pinfunction "STAT")
			(pintype "output+no_connect")
		)
		(pad "5" smd roundrect
			(at -0.003 1.214 90)
			(size 0.55 1)
			(layers "B.Cu" "B.Mask" "B.Paste")
			(roundrect_rratio 0.15)
			(net 1201 "Net-(Q23-G)")
			(pinfunction "GATE")
			(pintype "output")
		)
		(pad "6" smd roundrect
			(at -0.954 1.214 90)
			(size 0.55 1)
			(layers "B.Cu" "B.Mask" "B.Paste")
			(roundrect_rratio 0.15)
			(net 13 "VCC")
			(pinfunction "SENSE")
			(pintype "input")
		)
	)
	(footprint "antmicro-footprints:C_0402_1005Metric"
		(layer "B.Cu")
		(at 113.92 70.61)
		(descr "Capacitor SMD 0402")
		(tags "capacitor SMD 0402")
		(property "Reference" "C16"
			(at -0.82 0.69 0)
			(layer "B.SilkS")
			(effects
				(font
					(size 0.7 0.7)
					(thickness 0.15)
				)
				(justify right top mirror)
			)
		)
		(property "Value" "C_10u_0402"
			(at -1.022927 -2.155213 0)
			(layer "B.Fab")
			(effects
				(font
					(size 0.7 0.7)
					(thickness 0.15)
				)
				(justify right top mirror)
			)
		)
		(property "Datasheet" "https://www.yageo.com/en/Chart/Download/pdf/CC0402MRX5R5BB106"
			(at 0 0 0)
			(layer "B.Fab")
			(hide yes)
			(effects
				(font
					(size 1.27 1.27)
					(thickness 0.15)
				)
				(justify mirror)
			)
		)
		(property "Description" "SMD Multilayer Ceramic Capacitor, 10 µF, 6.3 V, 0402 [1005 Metric], ± 20%, X5R, CC Series"
			(at 0 0 0)
			(layer "B.Fab")
			(hide yes)
			(effects
				(font
					(size 1.27 1.27)
					(thickness 0.15)
				)
				(justify mirror)
			)
		)
		(property "MPN" "CC0402MRX5R5BB106"
			(at 0 0 0)
			(unlocked yes)
			(layer "B.Fab")
			(hide yes)
			(effects
				(font
					(size 1 1)
					(thickness 0.15)
				)
				(justify mirror)
			)
		)
		(property "Manufacturer" "YAGEO"
			(at 0 0 0)
			(unlocked yes)
			(layer "B.Fab")
			(hide yes)
			(effects
				(font
					(size 1 1)
					(thickness 0.15)
				)
				(justify mirror)
			)
		)
		(property "License" "Apache-2.0"
			(at 0 0 0)
			(unlocked yes)
			(layer "B.Fab")
			(hide yes)
			(effects
				(font
					(size 1 1)
					(thickness 0.15)
				)
				(justify mirror)
			)
		)
		(property "Author" "Antmicro"
			(at 0 0 0)
			(unlocked yes)
			(layer "B.Fab")
			(hide yes)
			(effects
				(font
					(size 1 1)
					(thickness 0.15)
				)
				(justify mirror)
			)
		)
		(property "Val" "10u"
			(at 0 0 0)
			(unlocked yes)
			(layer "B.Fab")
			(hide yes)
			(effects
				(font
					(size 1 1)
					(thickness 0.15)
				)
				(justify mirror)
			)
		)
		(property "Voltage" ""
			(at 0 0 0)
			(unlocked yes)
			(layer "B.Fab")
			(hide yes)
			(effects
				(font
					(size 1 1)
					(thickness 0.15)
				)
				(justify mirror)
			)
		)
		(property "Dielectric" "template_dielectric"
			(at 0 0 0)
			(unlocked yes)
			(layer "B.Fab")
			(hide yes)
			(effects
				(font
					(size 1 1)
					(thickness 0.15)
				)
				(justify mirror)
			)
		)
		(sheetname "/SoM_Power/")
		(sheetfile "som_power.kicad_sch")
		(attr smd)
		(fp_rect
			(start -0.925 0.47)
			(end 0.925 -0.47)
			(stroke
				(width 0.05)
				(type default)
			)
			(fill no)
			(layer "B.CrtYd")
		)
		(fp_line
			(start -0.494 -0.248)
			(end -0.494 0.25)
			(stroke
				(width 0.15)
				(type solid)
			)
			(layer "B.Fab")
		)
		(fp_line
			(start -0.494 0.25)
			(end 0.504 0.25)
			(stroke
				(width 0.15)
				(type solid)
			)
			(layer "B.Fab")
		)
		(fp_line
			(start 0.504 -0.248)
			(end -0.494 -0.248)
			(stroke
				(width 0.15)
				(type solid)
			)
			(layer "B.Fab")
		)
		(fp_line
			(start 0.504 0.25)
			(end 0.504 -0.248)
			(stroke
				(width 0.15)
				(type solid)
			)
			(layer "B.Fab")
		)
		(fp_text user "License: Apache-2.0"
			(at -0.939 -5.799 0)
			(layer "B.Fab")
			(effects
				(font
					(size 0.7 0.7)
					(thickness 0.15)
				)
				(justify right top mirror)
			)
		)
		(fp_text user "${REFERENCE}"
			(at -0.939 -4.599 0)
			(layer "B.Fab")
			(effects
				(font
					(size 0.7 0.7)
					(thickness 0.15)
				)
				(justify right top mirror)
			)
		)
		(fp_text user "Author: Antmicro"
			(at -0.939 -3.399 0)
			(layer "B.Fab")
			(effects
				(font
					(size 0.7 0.7)
					(thickness 0.15)
				)
				(justify right top mirror)
			)
		)
		(pad "1" smd roundrect
			(at -0.48 0)
			(size 0.59 0.64)
			(layers "B.Cu" "B.Mask" "B.Paste")
			(roundrect_rratio 0.25)
			(net 1 "GND")
			(pintype "passive")
		)
		(pad "2" smd roundrect
			(at 0.48 0)
			(size 0.59 0.64)
			(layers "B.Cu" "B.Mask" "B.Paste")
			(roundrect_rratio 0.25)
			(net 213 "+5V_SOM")
			(pintype "passive")
		)
	)
)
